# T6G (Grand Teton) — schematic netlist excerpt (pin names and nets, part order shuffled) for the footprints in the layout excerpt that follows; sources: Cadence DE-HDL packaged netlist, KiCad conversion of 04192023_DAF0TMB3IC0_F0TG_MB_C_brd_V02_OCP.brd

C696  Q_CAP_DIFFBUS  DIFF BUS_0.22UF 6.3V 20% X6S  pkg C0201  page 67 : \1\ = P5E_CPU1_G1_TX_C_DN<6> ; \2\ = P5E_CPU1_G1_TX_DN<6>
PR77  Q_RES  8.87K 1% EMPTY  pkg 0402LF  page 201 : A = PVDDCR_CPU1_P0_LSET2 ; B = GND
R722  Q_RES  1K 1% EMPTY  pkg 0402LF  page 238 : A = MB_FRU_ADDR0 ; B = GND

(kicad_pcb
	(version 20260206)
	(generator "pcbnew")
	(generator_version "10.0")
	(general
		(thickness 1.6)
		(legacy_teardrops no)
	)
	(paper "A4")
	(title_block
		(title "04192023_DAF0TMB3IC0_F0TG_MB_C_brd_V02_OCP.brd")
		(comment 1 "Grand Teton / footprints 3824-3826 of 8354")
	)
	(layers
		(0 "F.Cu" signal "TOP")
		(4 "In1.Cu" signal "GND")
		(6 "In2.Cu" signal "IN1")
		(8 "In3.Cu" signal "GND1")
		(10 "In4.Cu" signal "IN2")
		(12 "In5.Cu" signal "GND2")
		(14 "In6.Cu" signal "IN3")
		(16 "In7.Cu" signal "GND3")
		(18 "In8.Cu" signal "VCC")
		(20 "In9.Cu" signal "VCC1")
		(22 "In10.Cu" signal "GND4")
		(24 "In11.Cu" signal "IN4")
		(26 "In12.Cu" signal "GND5")
		(28 "In13.Cu" signal "IN5")
		(30 "In14.Cu" signal "GND6")
		(32 "In15.Cu" signal "IN6")
		(34 "In16.Cu" signal "GND7")
		(2 "B.Cu" signal "BOTTOM")
		(9 "F.Adhes" user "F.Adhesive")
		(11 "B.Adhes" user "B.Adhesive")
		(13 "F.Paste" user "Package Geometry/Pastemask Top")
		(15 "B.Paste" user "Package Geometry/Pastemask Bottom")
		(5 "F.SilkS" user "Ref Des/Silkscreen Top")
		(7 "B.SilkS" user "Ref Des/Silkscreen Bottom")
		(1 "F.Mask" user "Board Geometry/Soldermask Top")
		(3 "B.Mask" user "Board Geometry/Soldermask Bottom")
		(17 "Dwgs.User" user "User.Drawings")
		(19 "Cmts.User" user "User.Comments")
		(21 "Eco1.User" user "User.Eco1")
		(23 "Eco2.User" user "User.Eco2")
		(25 "Edge.Cuts" user "Board Geometry/Outline")
		(27 "Margin" user)
		(31 "F.CrtYd" user "Package Geometry/Place Bound Top")
		(29 "B.CrtYd" user "Package Geometry/Place Bound Bottom")
		(35 "F.Fab" user "Ref Des/Assembly Top")
		(33 "B.Fab" user "Ref Des/Assembly Bottom")
	)
	(footprint ""
		(layer "F.Cu")
		(at 302.271938 -119.479568 180)
		(property "Reference" "R722"
			(at 0 0 180)
			(layer "F.SilkS")
			(hide yes)
			(effects
				(font
					(size 1.27 1.27)
				)
			)
		)
		(property "Value" ""
			(at 0 0 180)
			(layer "F.Fab")
			(effects
				(font
					(size 1.27 1.27)
				)
			)
		)
		(duplicate_pad_numbers_are_jumpers no)
		(fp_line
			(start 0.7874 0.4064)
			(end -0.7874 0.4064)
			(stroke
				(width 0.1524)
				(type default)
			)
			(layer "F.SilkS")
		)
		(fp_line
			(start 0.7874 -0.4064)
			(end 0.7874 0.4064)
			(stroke
				(width 0.1524)
				(type default)
			)
			(layer "F.SilkS")
		)
		(fp_line
			(start -0.7874 0.4064)
			(end -0.7874 -0.4064)
			(stroke
				(width 0.1524)
				(type default)
			)
			(layer "F.SilkS")
		)
		(fp_line
			(start -0.7874 -0.4064)
			(end 0.7874 -0.4064)
			(stroke
				(width 0.1524)
				(type default)
			)
			(layer "F.SilkS")
		)
		(fp_line
			(start 0.67945 0.3048)
			(end 0.120396 0.3048)
			(stroke
				(width 0.1)
				(type default)
			)
			(layer "F.Fab")
		)
		(fp_line
			(start 0.67945 -0.3048)
			(end 0.67945 0.3048)
			(stroke
				(width 0.1)
				(type default)
			)
			(layer "F.Fab")
		)
		(fp_line
			(start 0.12065 -0.2794)
			(end 0.12065 -0.3048)
			(stroke
				(width 0.1)
				(type default)
			)
			(layer "F.Fab")
		)
		(fp_line
			(start 0.12065 -0.3048)
			(end 0.67945 -0.3048)
			(stroke
				(width 0.1)
				(type default)
			)
			(layer "F.Fab")
		)
		(fp_line
			(start 0.120396 0.3048)
			(end 0.120396 0.2794)
			(stroke
				(width 0.1)
				(type default)
			)
			(layer "F.Fab")
		)
		(fp_line
			(start 0.120396 0.2794)
			(end -0.12065 0.2794)
			(stroke
				(width 0.1)
				(type default)
			)
			(layer "F.Fab")
		)
		(fp_line
			(start -0.12065 0.3048)
			(end -0.67945 0.3048)
			(stroke
				(width 0.1)
				(type default)
			)
			(layer "F.Fab")
		)
		(fp_line
			(start -0.12065 0.2794)
			(end -0.12065 0.3048)
			(stroke
				(width 0.1)
				(type default)
			)
			(layer "F.Fab")
		)
		(fp_line
			(start -0.12065 -0.2794)
			(end 0.12065 -0.2794)
			(stroke
				(width 0.1)
				(type default)
			)
			(layer "F.Fab")
		)
		(fp_line
			(start -0.12065 -0.305054)
			(end -0.12065 -0.2794)
			(stroke
				(width 0.1)
				(type default)
			)
			(layer "F.Fab")
		)
		(fp_line
			(start -0.67945 0.3048)
			(end -0.67945 -0.305054)
			(stroke
				(width 0.1)
				(type default)
			)
			(layer "F.Fab")
		)
		(fp_line
			(start -0.67945 -0.305054)
			(end -0.12065 -0.305054)
			(stroke
				(width 0.1)
				(type default)
			)
			(layer "F.Fab")
		)
		(pad "1" smd circle
			(at -0.40005 0 180)
			(size 0 0)
			(layers "F.Cu" "F.Mask" "F.Paste")
			(net "MB_FRU_ADDR0")
		)
		(pad "2" smd circle
			(at 0.40005 0 180)
			(size 0 0)
			(layers "F.Cu" "F.Mask" "F.Paste")
			(net "GND")
		)
	)
	(footprint ""
		(layer "F.Cu")
		(at 40.960294 -17.623536 90)
		(property "Reference" "C696"
			(at 0 0 90)
			(layer "F.SilkS")
			(hide yes)
			(effects
				(font
					(size 1.27 1.27)
				)
			)
		)
		(property "Value" ""
			(at 0 0 90)
			(layer "F.Fab")
			(effects
				(font
					(size 1.27 1.27)
				)
			)
		)
		(duplicate_pad_numbers_are_jumpers no)
		(fp_line
			(start 0.299974 -0.150114)
			(end 0.299974 0.150114)
			(stroke
				(width 0.1)
				(type default)
			)
			(layer "F.Fab")
		)
		(fp_line
			(start -0.299974 -0.150114)
			(end 0.299974 -0.150114)
			(stroke
				(width 0.1)
				(type default)
			)
			(layer "F.Fab")
		)
		(fp_line
			(start 0.299974 0.150114)
			(end -0.299974 0.150114)
			(stroke
				(width 0.1)
				(type default)
			)
			(layer "F.Fab")
		)
		(fp_line
			(start -0.299974 0.150114)
			(end -0.299974 -0.150114)
			(stroke
				(width 0.1)
				(type default)
			)
			(layer "F.Fab")
		)
		(pad "1" smd rect
			(at -0.2667 0 90)
			(size 0.3048 0.381)
			(layers "F.Cu" "F.Mask" "F.Paste")
			(net "P5E_CPU1_G1_TX_C_DN<6>")
		)
		(pad "2" smd rect
			(at 0.2667 0 90)
			(size 0.3048 0.381)
			(layers "F.Cu" "F.Mask" "F.Paste")
			(net "P5E_CPU1_G1_TX_DN<6>")
		)
	)
	(footprint ""
		(layer "F.Cu")
		(at 325.39686 -340.199726)
		(property "Reference" "PR77"
			(at 0 0 0)
			(layer "F.SilkS")
			(hide yes)
			(effects
				(font
					(size 1.27 1.27)
				)
			)
		)
		(property "Value" ""
			(at 0 0 0)
			(layer "F.Fab")
			(effects
				(font
					(size 1.27 1.27)
				)
			)
		)
		(duplicate_pad_numbers_are_jumpers no)
		(fp_line
			(start -0.7874 -0.4064)
			(end 0.7874 -0.4064)
			(stroke
				(width 0.1524)
				(type default)
			)
			(layer "F.SilkS")
		)
		(fp_line
			(start -0.7874 0.4064)
			(end -0.7874 -0.4064)
			(stroke
				(width 0.1524)
				(type default)
			)
			(layer "F.SilkS")
		)
		(fp_line
			(start 0.7874 -0.4064)
			(end 0.7874 0.4064)
			(stroke
				(width 0.1524)
				(type default)
			)
			(layer "F.SilkS")
		)
		(fp_line
			(start 0.7874 0.4064)
			(end -0.7874 0.4064)
			(stroke
				(width 0.1524)
				(type default)
			)
			(layer "F.SilkS")
		)
		(fp_line
			(start -0.67945 -0.305054)
			(end -0.12065 -0.305054)
			(stroke
				(width 0.1)
				(type default)
			)
			(layer "F.Fab")
		)
		(fp_line
			(start -0.67945 0.3048)
			(end -0.67945 -0.305054)
			(stroke
				(width 0.1)
				(type default)
			)
			(layer "F.Fab")
		)
		(fp_line
			(start -0.12065 -0.305054)
			(end -0.12065 -0.2794)
			(stroke
				(width 0.1)
				(type default)
			)
			(layer "F.Fab")
		)
		(fp_line
			(start -0.12065 -0.2794)
			(end 0.12065 -0.2794)
			(stroke
				(width 0.1)
				(type default)
			)
			(layer "F.Fab")
		)
		(fp_line
			(start -0.12065 0.2794)
			(end -0.12065 0.3048)
			(stroke
				(width 0.1)
				(type default)
			)
			(layer "F.Fab")
		)
		(fp_line
			(start -0.12065 0.3048)
			(end -0.67945 0.3048)
			(stroke
				(width 0.1)
				(type default)
			)
			(layer "F.Fab")
		)
		(fp_line
			(start 0.120396 0.2794)
			(end -0.12065 0.2794)
			(stroke
				(width 0.1)
				(type default)
			)
			(layer "F.Fab")
		)
		(fp_line
			(start 0.120396 0.3048)
			(end 0.120396 0.2794)
			(stroke
				(width 0.1)
				(type default)
			)
			(layer "F.Fab")
		)
		(fp_line
			(start 0.12065 -0.3048)
			(end 0.67945 -0.3048)
			(stroke
				(width 0.1)
				(type default)
			)
			(layer "F.Fab")
		)
		(fp_line
			(start 0.12065 -0.2794)
			(end 0.12065 -0.3048)
			(stroke
				(width 0.1)
				(type default)
			)
			(layer "F.Fab")
		)
		(fp_line
			(start 0.67945 -0.3048)
			(end 0.67945 0.3048)
			(stroke
				(width 0.1)
				(type default)
			)
			(layer "F.Fab")
		)
		(fp_line
			(start 0.67945 0.3048)
			(end 0.120396 0.3048)
			(stroke
				(width 0.1)
				(type default)
			)
			(layer "F.Fab")
		)
		(pad "1" smd circle
			(at -0.40005 0)
			(size 0 0)
			(layers "F.Cu" "F.Mask" "F.Paste")
			(net "PVDDCR_CPU1_P0_LSET2")
		)
		(pad "2" smd circle
			(at 0.40005 0)
			(size 0 0)
			(layers "F.Cu" "F.Mask" "F.Paste")
			(net "GND")
		)
	)
)
